# BASEBOARD_FAB2 (Tioga Pass) — schematic netlist excerpt (pin names and nets, part order shuffled) for the footprints in the layout excerpt that follows; sources: Cadence DE-HDL packaged netlist, KiCad conversion of Wiwynn_Tioga_Pass_MB.brd

RT23  RES  0 5.0% CHIP  pkg 0603  page 204 : A = VR_PVCCIN_CPU0_PH5_BOOT ; B = VR_PVCCIN_CPU0_PH5_BOOT_R
C8F15  CAP_A  0.01UF 25V 10% X7R  pkg 0402V  page 185 : A = SATA6G_S0_RX_DN ; B = P3E_PCH_M2_SATA6G_RX_R_DN
R8G5  RES  20.0 1% CHIP  pkg 0402  page 159 : A = SMB_OCP_LAN_STBY_LVC3_SDA_R ; B = SMB_OCP_LAN_STBY_LVC3_SDA

(kicad_pcb
	(version 20260206)
	(generator "pcbnew")
	(generator_version "10.0")
	(general
		(thickness 1.6)
		(legacy_teardrops no)
	)
	(paper "A4")
	(title_block
		(title "Wiwynn_Tioga_Pass_MB.brd")
		(comment 1 "Tioga Pass / footprints 1286-1288 of 4770")
	)
	(layers
		(0 "F.Cu" signal "TOP")
		(4 "In1.Cu" signal "L2GND")
		(6 "In2.Cu" signal "L3")
		(8 "In3.Cu" signal "L4GND")
		(10 "In4.Cu" signal "L5")
		(12 "In5.Cu" signal "L6GND")
		(14 "In6.Cu" signal "L7VCC")
		(16 "In7.Cu" signal "L8VCC")
		(18 "In8.Cu" signal "L9GND")
		(20 "In9.Cu" signal "L10")
		(22 "In10.Cu" signal "L11GND")
		(24 "In11.Cu" signal "L12")
		(26 "In12.Cu" signal "L13GND")
		(2 "B.Cu" signal "BOTTOM")
		(9 "F.Adhes" user "F.Adhesive")
		(11 "B.Adhes" user "B.Adhesive")
		(13 "F.Paste" user "Package Geometry/Pastemask Top")
		(15 "B.Paste" user "Package Geometry/Pastemask Bottom")
		(5 "F.SilkS" user "Ref Des/Silkscreen Top")
		(7 "B.SilkS" user "Ref Des/Silkscreen Bottom")
		(1 "F.Mask" user "Board Geometry/Soldermask Top")
		(3 "B.Mask" user "Board Geometry/Soldermask Bottom")
		(17 "Dwgs.User" user "User.Drawings")
		(19 "Cmts.User" user "User.Comments")
		(21 "Eco1.User" user "User.Eco1")
		(23 "Eco2.User" user "User.Eco2")
		(25 "Edge.Cuts" user "Board Geometry/Outline")
		(27 "Margin" user)
		(31 "F.CrtYd" user "Package Geometry/Place Bound Top")
		(29 "B.CrtYd" user "Package Geometry/Place Bound Bottom")
		(35 "F.Fab" user "Ref Des/Assembly Top")
		(33 "B.Fab" user "Ref Des/Assembly Bottom")
	)
	(footprint ""
		(layer "F.Cu")
		(at 377.5202 -30.629352 90)
		(property "Reference" "C8F15"
			(at -0.8382 -0.67818 90)
			(unlocked yes)
			(layer "F.SilkS")
			(effects
				(font
					(size 0.4064 0.254)
					(thickness 0.1524)
				)
				(justify left)
			)
		)
		(property "Value" ""
			(at 0 0 90)
			(layer "F.Fab")
			(effects
				(font
					(size 1.27 1.27)
				)
			)
		)
		(duplicate_pad_numbers_are_jumpers no)
		(fp_poly
			(pts
				(xy 0.3048 -0.1016) (xy 0.3048 0.9906) (xy -0.3048 0.9906) (xy -0.3048 -0.1016)
			)
			(stroke
				(width 0)
				(type default)
			)
			(fill no)
			(layer "F.CrtYd")
		)
		(fp_line
			(start 0.3048 -0.1016)
			(end -0.3048 -0.1016)
			(stroke
				(width 0.1)
				(type default)
			)
			(layer "F.Fab")
		)
		(fp_line
			(start -0.3048 -0.1016)
			(end -0.3048 0.9906)
			(stroke
				(width 0.1)
				(type default)
			)
			(layer "F.Fab")
		)
		(fp_line
			(start 0.3048 0.9906)
			(end 0.3048 -0.1016)
			(stroke
				(width 0.1)
				(type default)
			)
			(layer "F.Fab")
		)
		(fp_line
			(start -0.3048 0.9906)
			(end 0.3048 0.9906)
			(stroke
				(width 0.1)
				(type default)
			)
			(layer "F.Fab")
		)
		(pad "1" smd rect
			(at 0 0 90)
			(size 0.508 0.508)
			(layers "F.Cu" "F.Mask" "F.Paste")
			(net "SATA6G_S0_RX_DN")
		)
		(pad "2" smd rect
			(at 0 0.889 90)
			(size 0.508 0.508)
			(layers "F.Cu" "F.Mask" "F.Paste")
			(net "P3E_PCH_M2_SATA6G_RX_R_DN")
		)
		(zone
			(layer "F.Cu")
			(hatch none 0.5)
			(connect_pads
				(clearance 0)
			)
			(min_thickness 0.25)
			(keepout
				(tracks allowed)
				(vias not_allowed)
				(pads allowed)
				(copperpour not_allowed)
				(footprints allowed)
			)
			(placement
				(enabled no)
				(sheetname "")
			)
			(fill
				(thermal_gap 0.5)
				(thermal_bridge_width 0.5)
				(island_removal_mode 0)
			)
			(polygon
				(pts
					(xy 377.7742 -30.375352) (xy 377.7742 -30.883352) (xy 378.1552 -30.883352) (xy 378.1552 -30.375352)
				)
			)
		)
		(zone
			(layer "F.Cu")
			(hatch none 0.5)
			(connect_pads
				(clearance 0)
			)
			(min_thickness 0.25)
			(keepout
				(tracks not_allowed)
				(vias allowed)
				(pads allowed)
				(copperpour not_allowed)
				(footprints allowed)
			)
			(placement
				(enabled no)
				(sheetname "")
			)
			(fill
				(thermal_gap 0.5)
				(thermal_bridge_width 0.5)
				(island_removal_mode 0)
			)
			(polygon
				(pts
					(xy 378.1552 -30.375352) (xy 378.1552 -30.883352) (xy 377.7742 -30.883352) (xy 377.7742 -30.375352)
				)
			)
		)
	)
	(footprint ""
		(layer "F.Cu")
		(at 192.62725 -90.3859 90)
		(property "Reference" "RT23"
			(at 1.01473 0.656336 0)
			(unlocked yes)
			(layer "F.SilkS")
			(effects
				(font
					(size 0.4064 0.254)
					(thickness 0.1524)
				)
			)
		)
		(property "Value" ""
			(at 0 0 90)
			(layer "F.Fab")
			(effects
				(font
					(size 1.27 1.27)
				)
			)
		)
		(duplicate_pad_numbers_are_jumpers no)
		(fp_poly
			(pts
				(xy -0.4953 -0.2032) (xy 0.4953 -0.2032) (xy 0.4953 1.6002) (xy -0.4953 1.6002)
			)
			(stroke
				(width 0)
				(type default)
			)
			(fill no)
			(layer "F.CrtYd")
		)
		(fp_line
			(start 0.4953 -0.2032)
			(end 0.4953 1.6002)
			(stroke
				(width 0.1)
				(type default)
			)
			(layer "F.Fab")
		)
		(fp_line
			(start -0.4953 -0.2032)
			(end 0.4953 -0.2032)
			(stroke
				(width 0.1)
				(type default)
			)
			(layer "F.Fab")
		)
		(fp_line
			(start 0.4953 1.6002)
			(end -0.4953 1.6002)
			(stroke
				(width 0.1)
				(type default)
			)
			(layer "F.Fab")
		)
		(fp_line
			(start -0.4953 1.6002)
			(end -0.4953 -0.2032)
			(stroke
				(width 0.1)
				(type default)
			)
			(layer "F.Fab")
		)
		(pad "1" smd rect
			(at 0 0 90)
			(size 0.762 0.889)
			(layers "F.Cu" "F.Mask" "F.Paste")
			(net "VR_PVCCIN_CPU0_PH5_BOOT")
		)
		(pad "2" smd rect
			(at 0 1.397 90)
			(size 0.762 0.889)
			(layers "F.Cu" "F.Mask" "F.Paste")
			(net "VR_PVCCIN_CPU0_PH5_BOOT_R")
		)
		(zone
			(layer "F.Cu")
			(hatch none 0.5)
			(connect_pads
				(clearance 0)
			)
			(min_thickness 0.25)
			(keepout
				(tracks allowed)
				(vias not_allowed)
				(pads allowed)
				(copperpour not_allowed)
				(footprints allowed)
			)
			(placement
				(enabled no)
				(sheetname "")
			)
			(fill
				(thermal_gap 0.5)
				(thermal_bridge_width 0.5)
				(island_removal_mode 0)
			)
			(polygon
				(pts
					(xy 193.57975 -90.7669) (xy 193.07175 -90.7669) (xy 193.07175 -90.0049) (xy 193.57975 -90.0049)
				)
			)
		)
		(zone
			(layer "F.Cu")
			(hatch none 0.5)
			(connect_pads
				(clearance 0)
			)
			(min_thickness 0.25)
			(keepout
				(tracks not_allowed)
				(vias allowed)
				(pads allowed)
				(copperpour not_allowed)
				(footprints allowed)
			)
			(placement
				(enabled no)
				(sheetname "")
			)
			(fill
				(thermal_gap 0.5)
				(thermal_bridge_width 0.5)
				(island_removal_mode 0)
			)
			(polygon
				(pts
					(xy 193.57975 -90.0049) (xy 193.57975 -90.7669) (xy 193.07175 -90.7669) (xy 193.07175 -90.0049)
				)
			)
		)
	)
	(footprint ""
		(layer "F.Cu")
		(at 399.758916 -35.041586 -90)
		(property "Reference" "R8G5"
			(at 0 0 270)
			(layer "F.SilkS")
			(hide yes)
			(effects
				(font
					(size 1.27 1.27)
				)
			)
		)
		(property "Value" ""
			(at 0 0 270)
			(layer "F.Fab")
			(effects
				(font
					(size 1.27 1.27)
				)
			)
		)
		(duplicate_pad_numbers_are_jumpers no)
		(fp_poly
			(pts
				(xy -0.2794 -0.1016) (xy 0.2794 -0.1016) (xy 0.2794 0.9906) (xy -0.2794 0.9906)
			)
			(stroke
				(width 0)
				(type default)
			)
			(fill no)
			(layer "F.CrtYd")
		)
		(fp_line
			(start -0.2794 0.9906)
			(end 0.2794 0.9906)
			(stroke
				(width 0.1)
				(type default)
			)
			(layer "F.Fab")
		)
		(fp_line
			(start 0.2794 0.9906)
			(end 0.2794 -0.1016)
			(stroke
				(width 0.1)
				(type default)
			)
			(layer "F.Fab")
		)
		(fp_line
			(start -0.2794 -0.1016)
			(end -0.2794 0.9906)
			(stroke
				(width 0.1)
				(type default)
			)
			(layer "F.Fab")
		)
		(fp_line
			(start 0.2794 -0.1016)
			(end -0.2794 -0.1016)
			(stroke
				(width 0.1)
				(type default)
			)
			(layer "F.Fab")
		)
		(pad "1" smd rect
			(at 0 0 270)
			(size 0.508 0.508)
			(layers "F.Cu" "F.Mask" "F.Paste")
			(net "SMB_OCP_LAN_STBY_LVC3_SDA_R")
		)
		(pad "2" smd rect
			(at 0 0.889 270)
			(size 0.508 0.508)
			(layers "F.Cu" "F.Mask" "F.Paste")
			(net "SMB_OCP_LAN_STBY_LVC3_SDA")
		)
		(zone
			(layer "F.Cu")
			(hatch none 0.5)
			(connect_pads
				(clearance 0)
			)
			(min_thickness 0.25)
			(keepout
				(tracks not_allowed)
				(vias allowed)
				(pads allowed)
				(copperpour not_allowed)
				(footprints allowed)
			)
			(placement
				(enabled no)
				(sheetname "")
			)
			(fill
				(thermal_gap 0.5)
				(thermal_bridge_width 0.5)
				(island_removal_mode 0)
			)
			(polygon
				(pts
					(xy 399.123916 -35.295586) (xy 399.123916 -34.787586) (xy 399.504916 -34.787586) (xy 399.504916 -35.295586)
				)
			)
		)
		(zone
			(layer "F.Cu")
			(hatch none 0.5)
			(connect_pads
				(clearance 0)
			)
			(min_thickness 0.25)
			(keepout
				(tracks allowed)
				(vias not_allowed)
				(pads allowed)
				(copperpour not_allowed)
				(footprints allowed)
			)
			(placement
				(enabled no)
				(sheetname "")
			)
			(fill
				(thermal_gap 0.5)
				(thermal_bridge_width 0.5)
				(island_removal_mode 0)
			)
			(polygon
				(pts
					(xy 399.504916 -35.295586) (xy 399.504916 -34.787586) (xy 399.123916 -34.787586) (xy 399.123916 -35.295586)
				)
			)
		)
	)
)
